G04 ================== begin FILE IDENTIFICATION RECORD ==================*
G04 Layout Name:  D:/<user>/Wistron_project/16347-sc/gbr/16347-sc.brd*
G04 Film Name:    L1*
G04 File Format:  Gerber RS274X*
G04 File Origin:  Cadence Allegro 16.5-S056*
G04 Origin Date:  Tue Mar 14 17:08:22 2017*
G04 *
G04 Layer:  VIA CLASS/TOP*
G04 Layer:  PIN/TOP*
G04 Layer:  ETCH/TOP*
G04 Layer:  DRAWING FORMAT/LAYER_PCB_STORY*
G04 Layer:  DRAWING FORMAT/LAYER_L1*
G04 *
G04 Offset:    (0.00 0.00)*
G04 Mirror:    No*
G04 Mode:      Positive*
G04 Rotation:  0*
G04 FullContactRelief:  No*
G04 UndefLineWidth:     6.00*
G04 ================== end FILE IDENTIFICATION RECORD ====================*
%FSLAX35Y35*MOIN*%
%IR0*IPPOS*OFA0.00000B0.00000*MIA0B0*SFA1.00000B1.00000*%
%ADD10C,.01*%
%ADD13C,.04*%
%ADD12C,.022*%
%ADD15C,.026*%
%ADD14R,.028X.034*%
%ADD11C,.237*%
%ADD16R,.272X.272*%
%ADD17C,.02*%
%ADD18C,.005*%
%ADD19C,.006*%
%ADD24C,.09204*%
%ADD25O,.48404X.06404*%
%ADD23C,.11004*%
%ADD21C,.26104*%
%ADD22C,.13904*%
%ADD20R,.29604X.29604*%
G75*
%LPD*%
G75*
G36*
G01X168202Y19235D02*
X202551Y53584D01*
X216388D01*
X218504Y51468D01*
Y38609D01*
X218558Y38556D01*
Y35682D01*
X236028Y18212D01*
X240033D01*
X240576Y17668D01*
X283197D01*
G03Y24072I0J3202D01*
G01X243143D01*
G03X241362Y24614I-1782J-2660D01*
G01X238680D01*
X227611Y35683D01*
G02X227894Y36366I283J283D01*
G01X276266D01*
X276269Y36369D01*
X282283D01*
G03X289221Y43307I0J6938D01*
G01Y63788D01*
G02X290157Y64716I936J-8D01*
G01X293411D01*
X293712Y64415D01*
Y55233D01*
X293711Y55224D01*
G03Y54834I2294J-195D01*
G01X293712Y54825D01*
Y53088D01*
X297800Y49000D01*
X299232D01*
X302395Y45837D01*
X305035D01*
X309987Y50789D01*
Y64325D01*
X310378Y64716D01*
X313780D01*
G02X314716Y63791I-18J-954D01*
G01Y43307D01*
G03X321654Y36369I6938J0D01*
G01X406496D01*
G03X413434Y43307I0J6938D01*
G01Y63783D01*
G02X414371Y64715I937J-5D01*
G01X417921D01*
X418324Y64312D01*
Y52633D01*
X421257Y49700D01*
X424142D01*
G03X424280I69J2300D01*
G01X431800D01*
X434200Y52100D01*
Y64197D01*
X434719Y64716D01*
X437994D01*
G02X438928Y63781I-1J-935D01*
G01Y43307D01*
G03X445866Y36369I6938J0D01*
G01X530709D01*
G03X537647Y43307I0J6938D01*
G01Y63789D01*
G02X538583Y64716I936J-9D01*
G01X542369D01*
X542465Y64620D01*
Y51335D01*
X544100Y49700D01*
X548355D01*
G03X548493I69J2300D01*
G01X556300D01*
X558500Y51900D01*
Y64597D01*
X558619Y64716D01*
X562205D01*
G02X563141Y63786I0J-936D01*
G01Y43307D01*
G03X570079Y36369I6938J0D01*
G01X654921D01*
G03X661859Y43307I0J6938D01*
G01Y63780D01*
G02X662795Y64716I936J0D01*
G01X665633D01*
X666062Y64287D01*
Y52836D01*
X668898Y50000D01*
X680105D01*
X682438Y52334D01*
X682528Y52424D01*
Y64446D01*
X682797Y64715D01*
X686443D01*
G02X687353Y63785I-37J-946D01*
G01Y43307D01*
G03X694291Y36369I6938J0D01*
G01X724409D01*
G02X725345Y35433I0J-936D01*
G01Y23698D01*
G02X724563Y23579I-400J0D01*
G03Y15789I-12457J-3895D01*
G02X725345Y15670I382J-119D01*
G01Y0D01*
G02X724409Y-936I-936J0D01*
G01X3937D01*
G02X3001Y0I0J936D01*
G01Y15670D01*
G02X3783Y15789I400J0D01*
G03Y23579I12457J3895D01*
G02X3001Y23698I-382J119D01*
G01Y35433D01*
G02X3937Y36369I936J0D01*
G01X33858D01*
G03X40796Y43307I0J6938D01*
G01Y63783D01*
G02X41733Y64716I937J-4D01*
G01X45241D01*
X45470Y64487D01*
Y51030D01*
X47300Y49200D01*
X60500D01*
X61500Y50200D01*
Y64586D01*
X61630Y64716D01*
X65364D01*
G02X66290Y63791I-14J-940D01*
G01Y43307D01*
G03X73228Y36369I6938J0D01*
G01X100031D01*
X100300Y36100D01*
Y30501D01*
X100299Y30482D01*
Y30475D01*
X100298Y30465D01*
G03X100296Y30002I2288J-241D01*
G01X100297Y29993D01*
Y29992D01*
X100300Y29962D01*
Y28800D01*
X101231Y27869D01*
X111389D01*
X111415Y27862D01*
G03X112633I609J2218D01*
G01X112659Y27869D01*
X125225D01*
X125260Y27855D01*
G03X126952I846J2141D01*
G01X126987Y27869D01*
X134565D01*
X134602Y27853D01*
G03X136398I898J2123D01*
G01X136435Y27869D01*
X154380D01*
X163014Y19235D01*
X168202D01*
G37*
G36*
G01X200950Y54699D02*
X166818Y20567D01*
X163962D01*
X160784Y23745D01*
Y24734D01*
X177558Y41508D01*
X177604Y41523D01*
G03X179216Y43135I-769J2381D01*
G01X179231Y43181D01*
X190200Y54150D01*
Y64639D01*
X190611Y65050D01*
X200550D01*
X200950Y64650D01*
Y54699D01*
G37*
G36*
G01X163510Y49296D02*
X163042Y49764D01*
Y67724D01*
G02X163976Y68652I950J-22D01*
G01X223048D01*
G02X223967Y67733I-22J-941D01*
G01Y58636D01*
X223708Y58377D01*
X222279D01*
X218087Y62569D01*
Y62583D01*
X206171D01*
X202354Y66400D01*
X172844D01*
X171204Y64760D01*
Y51552D01*
X168948Y49296D01*
X163510D01*
G37*
%LPC*%
G75*
G36*
G01X575564Y18236D02*
X574426Y17098D01*
X531500D01*
G02Y23502I0J3202D01*
G01X572186D01*
G02X575564Y18236I1114J-3002D01*
G37*
G36*
G01X665500Y22902D02*
G02Y16498I0J-3202D01*
G01X624094D01*
X624071Y16493D01*
G02X621036Y21864I-771J3107D01*
G01X622074Y22902D01*
X665500D01*
G37*
G36*
G01X139300Y15798D02*
X103826D01*
X102264Y14236D01*
G02X100000Y13298I-2264J2263D01*
G01X93774D01*
X90374Y16698D01*
X59871D01*
G02Y23102I0J3202D01*
G01X93026D01*
X96426Y19702D01*
X98674D01*
X101174Y22202D01*
X139300D01*
G02Y15798I0J-3202D01*
G37*
G54D24*
X693601Y10159D03*
X35851Y28624D03*
G54D25*
X426000Y20700D03*
G54D23*
X693024Y26550D03*
X35185Y15572D03*
G54D21*
X488681Y19684D03*
X301968Y19685D03*
G54D22*
X680610D03*
X47737D03*
G54D20*
X597500Y20000D03*
%LPD*%
G75*
G54D10*
X35185Y15572D03*
X47737Y19685D03*
X16240Y99213D03*
Y233859D03*
Y368505D03*
Y503151D03*
Y637797D03*
Y772443D03*
Y907089D03*
X693024Y26550D03*
X680610Y19685D03*
X784745D03*
Y154331D03*
Y288977D03*
Y423623D03*
Y558269D03*
Y692915D03*
Y827561D03*
G54D11*
X16240Y19684D03*
X301968Y19685D03*
X488681Y19684D03*
X712106D03*
G54D12*
X38675Y22425D03*
X20459Y5682D03*
X35539Y4546D03*
X4758Y4649D03*
X41942Y46869D03*
X42071Y58644D03*
X5223Y34706D03*
X30374Y34551D03*
X90368Y245D03*
X63477Y4598D03*
X71000Y11600D03*
X84600Y12000D03*
X59871Y19900D03*
X59100Y56200D03*
X55513Y51513D03*
X47800Y56500D03*
X51573Y51573D03*
X76200Y35200D03*
X65000Y45100D03*
X65100Y59000D03*
X54026Y28870D03*
X46376Y36160D03*
X113912Y245D03*
X124500Y12100D03*
X111100Y10400D03*
X100000Y16500D03*
X135500Y29976D03*
X126106Y29996D03*
X102586Y30227D03*
X112024Y30080D03*
X99000Y35000D03*
X145601Y245D03*
X179537Y9829D03*
X174542Y4205D03*
X140900Y23800D03*
X139300Y19000D03*
X162191Y24351D03*
X165593Y21701D03*
X175800Y67500D03*
X164200Y62000D03*
X164378Y52020D03*
X145200Y26300D03*
X225477Y20626D03*
X189652Y8444D03*
X202034Y4247D03*
X233765Y34883D03*
X219878Y32075D03*
X217446Y46840D03*
Y51035D03*
X222700Y60100D03*
X216500Y67500D03*
X197800D03*
X199700Y63910D03*
X195500D03*
X191500D03*
X249762Y12946D03*
X265042Y13093D03*
X238391Y14434D03*
X241359Y21413D03*
X238755Y26619D03*
X279170Y35245D03*
X256656Y35189D03*
X245853Y31620D03*
X323200Y13800D03*
X283197Y20870D03*
X307599Y54564D03*
X302200Y51718D03*
X296005Y55029D03*
X304088Y48291D03*
X290350Y46275D03*
X290660Y58851D03*
X316800Y35900D03*
X313200Y45500D03*
X313500Y58100D03*
X348900Y13700D03*
X330300Y26000D03*
X365800Y26400D03*
X339400Y34800D03*
X404600Y14400D03*
X383600Y14000D03*
X414700Y13800D03*
X405000Y20700D03*
X420635Y54538D03*
X424211Y52000D03*
X394400Y26300D03*
X402400Y34800D03*
X414600Y44600D03*
X414700Y58000D03*
X384600Y34800D03*
X455689Y15598D03*
X446135Y10537D03*
X428600Y13800D03*
X447000Y20700D03*
X431894Y54627D03*
X428151Y52151D03*
X436012Y59651D03*
X437768Y51052D03*
X438311Y39148D03*
X448019Y35172D03*
X462893D03*
X455817Y26237D03*
X516716Y15930D03*
X501900Y10348D03*
X473919Y10744D03*
X518856Y25583D03*
X503159Y35111D03*
X473300Y25875D03*
X563034Y312D03*
X532070Y10129D03*
X541225Y13900D03*
X554500Y13000D03*
X531500Y20300D03*
X555996Y54409D03*
X552364Y52136D03*
X544789Y54552D03*
X548424Y52000D03*
X565606Y36026D03*
X561619Y47946D03*
X561954Y58858D03*
X538954Y59320D03*
X538911Y42406D03*
X529979Y35111D03*
X601510Y277D03*
X614586Y25544D03*
X580014Y25376D03*
X580128Y14830D03*
X574168Y7737D03*
X573300Y20500D03*
X615510Y35060D03*
X581051Y35186D03*
X646777Y311D03*
X628333Y278D03*
X662275Y4597D03*
X625457Y14410D03*
X617398Y7695D03*
X632900Y13300D03*
X647600Y12500D03*
X623300Y19600D03*
X644052Y35251D03*
X663106Y43749D03*
X663022Y59320D03*
X695912Y18399D03*
X671342Y13872D03*
X704646Y4135D03*
X684016Y4178D03*
X665500Y19700D03*
X680189Y54619D03*
X676576Y52380D03*
X668373Y54326D03*
X672636Y52380D03*
X685686Y59530D03*
X686484Y39279D03*
X701971Y35249D03*
X670753Y27514D03*
X724174Y4463D03*
X723902Y35018D03*
G54D13*
G01X100000Y16500D02*
X95100D01*
X91700Y19900D01*
X59871D01*
G01X139300Y19000D02*
X102500D01*
X100000Y16500D01*
G01X241359Y21413D02*
X237354D01*
X221759Y37008D01*
Y53388D01*
X215957Y59190D01*
X199802D01*
G01X283197Y20870D02*
X241902D01*
X241359Y21413D01*
G01X447000Y20700D02*
X405000D01*
G01X531500Y20300D02*
X573100D01*
X573300Y20500D01*
G01X623300Y19600D02*
X623400Y19700D01*
X665500D01*
X35851Y28624D03*
X48411Y920770D03*
X693601Y10159D03*
X751130Y826309D03*
X765026Y19107D03*
G54D14*
X55513Y61930D03*
X51573D03*
X55513Y56180D03*
X51573D03*
X179726Y61930D03*
X175786D03*
X179726Y56180D03*
X175786D03*
X303939Y61930D03*
X299999D03*
X303939Y56180D03*
X299999D03*
X424211Y61930D03*
Y56180D03*
X428151Y61930D03*
Y56180D03*
X552364Y61930D03*
X548424D03*
X552364Y56180D03*
X548424D03*
X676576Y61930D03*
X672636D03*
X676576Y56180D03*
X672636D03*
G54D15*
X53632Y45628D03*
X97400Y24300D03*
X176835Y43904D03*
X179708Y49915D03*
X173169Y49700D03*
X171596Y44154D03*
X207900Y43000D03*
X296600Y47000D03*
X387700Y23700D03*
X422646Y46356D03*
X548049Y46414D03*
X671209Y45487D03*
G54D16*
X597500Y20000D03*
G54D17*
G01X-23515Y-108314D02*
X-55515D01*
G01X-23515Y-124314D02*
Y-204314D01*
G01D02*
X1177585D01*
G01X-27515Y-108314D02*
G02I-12000J0D01*
G01X-39515Y-124314D02*
Y-92314D01*
G01X-23515Y-124314D02*
X1177585D01*
G01X-23515Y-159814D02*
X1177585D01*
G01X-32665Y-108314D02*
G02I-6850J0D01*
G01X390085Y-124314D02*
Y-204314D01*
G01X527585Y-124314D02*
Y-204314D01*
G01X642585Y-124314D02*
Y-204314D01*
G01X810085Y-124314D02*
Y-204314D01*
G01X980085Y-124314D02*
Y-204314D01*
G01X1177585Y-124314D02*
Y-204314D01*
G01X1205585Y-108314D02*
G02I-12000J0D01*
G01X1200435D02*
G02I-6850J0D01*
G01X1209585D02*
X1177585D01*
G01X1193585Y-124314D02*
Y-92314D01*
G54D18*
G01X59100Y56200D02*
Y60100D01*
X57270Y61930D01*
X55513D01*
G01Y56180D02*
Y51513D01*
G01X47800Y56500D02*
Y58800D01*
X50930Y61930D01*
X51573D01*
G01Y56180D02*
Y51573D01*
G01X135500Y29976D02*
X135539Y30015D01*
X162946D01*
X176835Y43904D01*
G01X126106Y29996D02*
X128243Y32133D01*
X162787D01*
X174046Y43392D01*
Y44253D01*
X179708Y49915D01*
G01X102586Y30227D02*
X108367Y36008D01*
X159955D01*
X173169Y49222D01*
Y49700D01*
G01X112024Y30080D02*
X116296Y34352D01*
X161794D01*
X171596Y44154D01*
G01X179726Y61930D02*
X181668D01*
X182838Y60760D01*
Y49907D01*
X176835Y43904D01*
G01X179726Y56180D02*
Y49933D01*
X179708Y49915D01*
G01X175786Y61930D02*
X174157D01*
X173183Y60956D01*
Y51080D01*
X173169Y51066D01*
Y49700D01*
G01X175786Y56180D02*
Y48344D01*
X171596Y44154D01*
G01X307599Y54564D02*
Y59210D01*
X304879Y61930D01*
X303939D01*
G01X302200Y51718D02*
X303939Y53457D01*
Y56180D01*
G01X296005Y55029D02*
Y59005D01*
X298930Y61930D01*
X299999D01*
G01X304088Y48291D02*
X302597D01*
X299999Y50889D01*
Y56180D01*
G01X420635Y54538D02*
Y60373D01*
X422192Y61930D01*
X424211D01*
G01X431894Y54627D02*
Y59636D01*
X429600Y61930D01*
X428151D01*
G01Y56180D02*
Y52151D01*
G01X424211Y56180D02*
Y52000D01*
G01X555996Y54409D02*
Y60735D01*
X554801Y61930D01*
X552364D01*
G01Y56180D02*
Y52136D01*
G01X544789Y54552D02*
X544800Y54563D01*
Y60300D01*
X546430Y61930D01*
X548424D01*
G01Y56180D02*
Y52000D01*
G01X680189Y54619D02*
Y60432D01*
X678691Y61930D01*
X676576D01*
G01Y56180D02*
Y52380D01*
G01X668373Y54326D02*
Y58670D01*
X671633Y61930D01*
X672636D01*
G01Y56180D02*
Y52380D01*
G54D19*
G01X981Y-184981D02*
X1855Y-184106D01*
X2510Y-182648D01*
X2947Y-180605D01*
X2510Y-178856D01*
X1637Y-177689D01*
X108Y-176814D01*
X-5787D01*
Y-194314D01*
X1418D01*
X2947Y-193148D01*
X3820Y-191397D01*
X4257Y-189356D01*
X3820Y-187314D01*
X2510Y-185564D01*
X981Y-184981D01*
X-5787D01*
G01X13678Y-194314D02*
Y-182648D01*
G01Y-184981D02*
X14770Y-183814D01*
X15862Y-182939D01*
X17390Y-182648D01*
X18481Y-182939D01*
X19792Y-183814D01*
G01X29650Y-199564D02*
X30960Y-200147D01*
X32707Y-199564D01*
X33798Y-198398D01*
X34672Y-196939D01*
X35981Y-192273D01*
X38820Y-182648D01*
G01X31833D02*
X35981Y-192273D01*
G01X55228Y-184106D02*
X53700Y-182939D01*
X52390Y-182648D01*
X50643Y-183231D01*
X49333Y-184397D01*
X48460Y-186439D01*
X48241Y-188481D01*
X48460Y-190523D01*
X49333Y-192273D01*
X50643Y-193731D01*
X52390Y-194314D01*
X53918Y-193731D01*
X55228Y-192564D01*
G01X65960Y-186439D02*
X72947D01*
X72292Y-184397D01*
X71200Y-183231D01*
X69672Y-182648D01*
X68143Y-182939D01*
X66833Y-183814D01*
X65960Y-185856D01*
X65523Y-187606D01*
Y-189356D01*
X65960Y-191106D01*
X67052Y-192856D01*
X68362Y-194022D01*
X69890Y-194314D01*
X71418Y-193731D01*
X72947Y-191981D01*
G01X109038Y-178273D02*
X107728Y-177397D01*
X106200Y-176814D01*
X104453D01*
X102488Y-177689D01*
X100960Y-179147D01*
X99868Y-180898D01*
X98995Y-183814D01*
X98776Y-186439D01*
X99213Y-189064D01*
X99868Y-190814D01*
X101178Y-192564D01*
X102707Y-193731D01*
X104235Y-194314D01*
X105763D01*
X107292Y-193731D01*
X108602Y-192856D01*
X109694Y-191690D01*
G01X125665Y-194314D02*
Y-182648D01*
G01Y-184689D02*
X124792Y-183523D01*
X123481Y-182939D01*
X121953Y-182648D01*
X120425Y-183231D01*
X119115Y-184397D01*
X118241Y-186147D01*
X117805Y-188481D01*
X118241Y-190814D01*
X119115Y-192564D01*
X120425Y-193731D01*
X121953Y-194314D01*
X123481Y-194022D01*
X124792Y-193148D01*
X125665Y-191981D01*
G01X135523Y-194314D02*
Y-182648D01*
G01Y-185564D02*
X136397Y-184106D01*
X137707Y-182939D01*
X139453Y-182648D01*
X140981Y-182939D01*
X142292Y-184106D01*
X142947Y-186147D01*
Y-194314D01*
G01X152150Y-199564D02*
X153460Y-200147D01*
X155207Y-199564D01*
X156298Y-198398D01*
X157172Y-196939D01*
X158481Y-192273D01*
X161320Y-182648D01*
G01X154333D02*
X158481Y-192273D01*
G01X174235Y-194314D02*
X172925Y-194022D01*
X171615Y-192856D01*
X170741Y-190814D01*
X170305Y-188481D01*
X170741Y-186147D01*
X171615Y-184106D01*
X172925Y-182939D01*
X174235Y-182648D01*
X175545Y-182939D01*
X176855Y-184106D01*
X177728Y-186147D01*
X177947Y-188481D01*
X177728Y-190814D01*
X176855Y-192856D01*
X175545Y-194022D01*
X174235Y-194314D01*
G01X188023D02*
Y-182648D01*
G01Y-185564D02*
X188897Y-184106D01*
X190207Y-182939D01*
X191953Y-182648D01*
X193481Y-182939D01*
X194792Y-184106D01*
X195447Y-186147D01*
Y-194314D01*
G01X222368Y-176814D02*
Y-194314D01*
X231102D01*
G01X248602D02*
X239868D01*
Y-176814D01*
X248602D01*
G01X245108Y-185272D02*
X239868D01*
G01X256932Y-194314D02*
Y-176814D01*
X261298D01*
X263045Y-177689D01*
X264355Y-178856D01*
X265447Y-180605D01*
X266320Y-182648D01*
X266538Y-185564D01*
X266320Y-188481D01*
X265447Y-190523D01*
X264355Y-192273D01*
X263045Y-193439D01*
X261298Y-194314D01*
X256932D01*
G01X298481Y-184981D02*
X299355Y-184106D01*
X300010Y-182648D01*
X300447Y-180605D01*
X300010Y-178856D01*
X299137Y-177689D01*
X297608Y-176814D01*
X291713D01*
Y-194314D01*
X298918D01*
X300447Y-193148D01*
X301320Y-191397D01*
X301757Y-189356D01*
X301320Y-187314D01*
X300010Y-185564D01*
X298481Y-184981D01*
X291713D01*
G01X314235Y-194314D02*
X312925Y-194022D01*
X311615Y-192856D01*
X310741Y-190814D01*
X310305Y-188481D01*
X310741Y-186147D01*
X311615Y-184106D01*
X312925Y-182939D01*
X314235Y-182648D01*
X315545Y-182939D01*
X316855Y-184106D01*
X317728Y-186147D01*
X317947Y-188481D01*
X317728Y-190814D01*
X316855Y-192856D01*
X315545Y-194022D01*
X314235Y-194314D01*
G01X335665D02*
Y-182648D01*
G01Y-184689D02*
X334792Y-183523D01*
X333481Y-182939D01*
X331953Y-182648D01*
X330425Y-183231D01*
X329115Y-184397D01*
X328241Y-186147D01*
X327805Y-188481D01*
X328241Y-190814D01*
X329115Y-192564D01*
X330425Y-193731D01*
X331953Y-194314D01*
X333481Y-194022D01*
X334792Y-193148D01*
X335665Y-191981D01*
G01X346178Y-194314D02*
Y-182648D01*
G01Y-184981D02*
X347270Y-183814D01*
X348362Y-182939D01*
X349890Y-182648D01*
X350981Y-182939D01*
X352292Y-183814D01*
G01X370665Y-176814D02*
Y-194314D01*
G01Y-191690D02*
X369792Y-193148D01*
X368481Y-194022D01*
X366953Y-194314D01*
X365207Y-193731D01*
X363897Y-192273D01*
X363023Y-190523D01*
X362805Y-188481D01*
X363023Y-186439D01*
X363897Y-184689D01*
X365207Y-183231D01*
X366953Y-182648D01*
X368481Y-182939D01*
X369573Y-183523D01*
X370665Y-184689D01*
G01X142308Y-149314D02*
Y-131814D01*
X147985Y-146397D01*
X153662Y-131814D01*
Y-149314D01*
G01X165485D02*
X164175Y-149022D01*
X162865Y-147856D01*
X161991Y-145814D01*
X161555Y-143481D01*
X161991Y-141147D01*
X162865Y-139106D01*
X164175Y-137939D01*
X165485Y-137648D01*
X166795Y-137939D01*
X168105Y-139106D01*
X168978Y-141147D01*
X169197Y-143481D01*
X168978Y-145814D01*
X168105Y-147856D01*
X166795Y-149022D01*
X165485Y-149314D01*
G01X186915Y-131814D02*
Y-149314D01*
G01Y-146690D02*
X186042Y-148148D01*
X184731Y-149022D01*
X183203Y-149314D01*
X181457Y-148731D01*
X180147Y-147273D01*
X179273Y-145523D01*
X179055Y-143481D01*
X179273Y-141439D01*
X180147Y-139689D01*
X181457Y-138231D01*
X183203Y-137648D01*
X184731Y-137939D01*
X185823Y-138523D01*
X186915Y-139689D01*
G01X197210Y-141439D02*
X204197D01*
X203542Y-139397D01*
X202450Y-138231D01*
X200922Y-137648D01*
X199393Y-137939D01*
X198083Y-138814D01*
X197210Y-140856D01*
X196773Y-142606D01*
Y-144356D01*
X197210Y-146106D01*
X198302Y-147856D01*
X199612Y-149022D01*
X201140Y-149314D01*
X202668Y-148731D01*
X204197Y-146981D01*
G01X217985Y-149314D02*
Y-131814D01*
G01X423785Y-194314D02*
Y-176814D01*
X421165Y-180314D01*
G01Y-194314D02*
X426405D01*
G01X437137Y-187023D02*
X438665Y-184981D01*
X439975Y-183814D01*
X441722Y-183231D01*
X443250Y-183814D01*
X444342Y-184981D01*
X445215Y-186731D01*
X445433Y-188772D01*
X445215Y-190523D01*
X444342Y-192273D01*
X443031Y-193731D01*
X441503Y-194314D01*
X439757Y-193731D01*
X438228Y-191981D01*
X437355Y-189356D01*
X437137Y-186439D01*
X437573Y-182648D01*
X438228Y-180605D01*
X439320Y-178564D01*
X440848Y-177106D01*
X442377Y-176814D01*
X443905Y-177397D01*
X444997Y-178856D01*
G01X453982Y-190814D02*
X455291Y-192856D01*
X457038Y-194022D01*
X459003Y-194314D01*
X460750Y-194022D01*
X462497Y-192564D01*
X463588Y-190814D01*
X463807Y-189064D01*
X463370Y-187023D01*
X461842Y-185564D01*
X460313Y-184981D01*
X458348D01*
G01X460313D02*
X461623Y-184106D01*
X462715Y-182648D01*
X463152Y-180898D01*
X462715Y-179147D01*
X461623Y-177689D01*
X459658Y-176814D01*
X457693Y-177106D01*
X455728Y-178273D01*
G01X478905Y-194314D02*
Y-176814D01*
X470826Y-189356D01*
X481744D01*
G01X493348Y-194314D02*
X493785Y-190523D01*
X494440Y-187314D01*
X495313Y-184397D01*
X496405Y-181189D01*
X498152Y-176814D01*
X489418D01*
G01X410668Y-149314D02*
Y-131814D01*
X415908D01*
X417655Y-132689D01*
X418965Y-134731D01*
X419402Y-137064D01*
X418965Y-139397D01*
X417873Y-141147D01*
X415908Y-142023D01*
X410668D01*
G01X437338Y-133273D02*
X436028Y-132397D01*
X434500Y-131814D01*
X432753D01*
X430788Y-132689D01*
X429260Y-134147D01*
X428168Y-135898D01*
X427295Y-138814D01*
X427076Y-141439D01*
X427513Y-144064D01*
X428168Y-145814D01*
X429478Y-147564D01*
X431007Y-148731D01*
X432535Y-149314D01*
X434063D01*
X435592Y-148731D01*
X436902Y-147856D01*
X437994Y-146690D01*
G01X451781Y-139981D02*
X452655Y-139106D01*
X453310Y-137648D01*
X453747Y-135605D01*
X453310Y-133856D01*
X452437Y-132689D01*
X450908Y-131814D01*
X445013D01*
Y-149314D01*
X452218D01*
X453747Y-148148D01*
X454620Y-146397D01*
X455057Y-144356D01*
X454620Y-142314D01*
X453310Y-140564D01*
X451781Y-139981D01*
X445013D01*
G01X460985Y-155147D02*
X474085D01*
G01X480013Y-149314D02*
Y-131814D01*
X490057Y-149314D01*
Y-131814D01*
G01X502535Y-149314D02*
X500788Y-149022D01*
X499260Y-147856D01*
X497950Y-146106D01*
X497076Y-144064D01*
X496640Y-141731D01*
Y-139397D01*
X497076Y-137064D01*
X497950Y-135022D01*
X499260Y-133273D01*
X500788Y-132106D01*
X502535Y-131814D01*
X504281Y-132106D01*
X505810Y-133273D01*
X507120Y-135022D01*
X507994Y-137064D01*
X508430Y-139397D01*
Y-141731D01*
X507994Y-144064D01*
X507120Y-146106D01*
X505810Y-147856D01*
X504281Y-149022D01*
X502535Y-149314D01*
G01X553376Y-131814D02*
X558835Y-149314D01*
X564294Y-131814D01*
G01X580702Y-149314D02*
X571968D01*
Y-131814D01*
X580702D01*
G01X577208Y-140272D02*
X571968D01*
G01X589468Y-149314D02*
Y-131814D01*
X594927D01*
X596673Y-132689D01*
X597765Y-133856D01*
X598202Y-136189D01*
X597765Y-138523D01*
X596455Y-139981D01*
X594927Y-140856D01*
X589468D01*
G01X594927D02*
X598202Y-149314D01*
G01X611335Y-149897D02*
X610898Y-149606D01*
Y-149022D01*
X611335Y-148731D01*
X611772Y-149022D01*
Y-149606D01*
X611335Y-149897D01*
G01X571750Y-191981D02*
X573497Y-193439D01*
X575462Y-194314D01*
X577208D01*
X578955Y-193439D01*
X580265Y-191981D01*
X580920Y-189939D01*
X580483Y-187898D01*
X579392Y-186147D01*
X577427Y-184981D01*
X574807Y-184397D01*
X573278Y-183231D01*
X572623Y-181189D01*
X573060Y-179147D01*
X574152Y-177689D01*
X575680Y-176814D01*
X577208D01*
X578737Y-177397D01*
X580047Y-178856D01*
G01X598638Y-178273D02*
X597328Y-177397D01*
X595800Y-176814D01*
X594053D01*
X592088Y-177689D01*
X590560Y-179147D01*
X589468Y-180898D01*
X588595Y-183814D01*
X588376Y-186439D01*
X588813Y-189064D01*
X589468Y-190814D01*
X590778Y-192564D01*
X592307Y-193731D01*
X593835Y-194314D01*
X595363D01*
X596892Y-193731D01*
X598202Y-192856D01*
X599294Y-191690D01*
G01X686918Y-131814D02*
Y-149314D01*
X695652D01*
G01X712715D02*
Y-137648D01*
G01Y-139689D02*
X711842Y-138523D01*
X710531Y-137939D01*
X709003Y-137648D01*
X707475Y-138231D01*
X706165Y-139397D01*
X705291Y-141147D01*
X704855Y-143481D01*
X705291Y-145814D01*
X706165Y-147564D01*
X707475Y-148731D01*
X709003Y-149314D01*
X710531Y-149022D01*
X711842Y-148148D01*
X712715Y-146981D01*
G01X721700Y-154564D02*
X723010Y-155147D01*
X724757Y-154564D01*
X725848Y-153398D01*
X726722Y-151939D01*
X728031Y-147273D01*
X730870Y-137648D01*
G01X723883D02*
X728031Y-147273D01*
G01X740510Y-141439D02*
X747497D01*
X746842Y-139397D01*
X745750Y-138231D01*
X744222Y-137648D01*
X742693Y-137939D01*
X741383Y-138814D01*
X740510Y-140856D01*
X740073Y-142606D01*
Y-144356D01*
X740510Y-146106D01*
X741602Y-147856D01*
X742912Y-149022D01*
X744440Y-149314D01*
X745968Y-148731D01*
X747497Y-146981D01*
G01X758228Y-149314D02*
Y-137648D01*
G01Y-139981D02*
X759320Y-138814D01*
X760412Y-137939D01*
X761940Y-137648D01*
X763031Y-137939D01*
X764342Y-138814D01*
G01X713168Y-176814D02*
Y-194314D01*
X721902D01*
G01X735035D02*
Y-176814D01*
X732415Y-180314D01*
G01Y-194314D02*
X737655D01*
G01X851335D02*
X849588Y-194022D01*
X848060Y-192856D01*
X846750Y-191106D01*
X845876Y-189064D01*
X845440Y-186731D01*
Y-184397D01*
X845876Y-182064D01*
X846750Y-180022D01*
X848060Y-178273D01*
X849588Y-177106D01*
X851335Y-176814D01*
X853081Y-177106D01*
X854610Y-178273D01*
X855920Y-180022D01*
X856794Y-182064D01*
X857230Y-184397D01*
Y-186731D01*
X856794Y-189064D01*
X855920Y-191106D01*
X854610Y-192856D01*
X853081Y-194022D01*
X851335Y-194314D01*
G01X853081Y-189647D02*
X855702Y-194314D01*
G01X864032Y-176814D02*
Y-189356D01*
X864905Y-191981D01*
X866652Y-193731D01*
X868835Y-194314D01*
X871018Y-193731D01*
X872765Y-191981D01*
X873638Y-189356D01*
Y-176814D01*
G01X883715D02*
X888955D01*
G01X886335D02*
Y-194314D01*
G01X883715D02*
X888955D01*
G01X898813D02*
Y-176814D01*
X908857Y-194314D01*
Y-176814D01*
G01X926138Y-178273D02*
X924828Y-177397D01*
X923300Y-176814D01*
X921553D01*
X919588Y-177689D01*
X918060Y-179147D01*
X916968Y-180898D01*
X916095Y-183814D01*
X915876Y-186439D01*
X916313Y-189064D01*
X916968Y-190814D01*
X918278Y-192564D01*
X919807Y-193731D01*
X921335Y-194314D01*
X922863D01*
X924392Y-193731D01*
X925702Y-192856D01*
X926794Y-191690D01*
G01X938835Y-194314D02*
Y-186439D01*
X934468Y-176814D01*
G01X943202D02*
X938835Y-186439D01*
G01X829032Y-149314D02*
Y-131814D01*
X833398D01*
X835145Y-132689D01*
X836455Y-133856D01*
X837547Y-135605D01*
X838420Y-137648D01*
X838638Y-140564D01*
X838420Y-143481D01*
X837547Y-145523D01*
X836455Y-147273D01*
X835145Y-148439D01*
X833398Y-149314D01*
X829032D01*
G01X848060Y-141439D02*
X855047D01*
X854392Y-139397D01*
X853300Y-138231D01*
X851772Y-137648D01*
X850243Y-137939D01*
X848933Y-138814D01*
X848060Y-140856D01*
X847623Y-142606D01*
Y-144356D01*
X848060Y-146106D01*
X849152Y-147856D01*
X850462Y-149022D01*
X851990Y-149314D01*
X853518Y-148731D01*
X855047Y-146981D01*
G01X865560Y-147273D02*
X866652Y-148439D01*
X868180Y-149314D01*
X869490D01*
X870800Y-148731D01*
X871673Y-147856D01*
X872110Y-146690D01*
X871892Y-144939D01*
X871018Y-144064D01*
X867088Y-142314D01*
X866215Y-140272D01*
X866652Y-138814D01*
X867525Y-137939D01*
X868835Y-137648D01*
X870145Y-137939D01*
X871455Y-138814D01*
G01X886335Y-137648D02*
Y-149314D01*
G01Y-132981D02*
X885898Y-132689D01*
Y-132106D01*
X886335Y-131814D01*
X886772Y-132106D01*
Y-132689D01*
X886335Y-132981D01*
G01X900778Y-153689D02*
X902307Y-154856D01*
X904053Y-155147D01*
X905581Y-154856D01*
X906892Y-153398D01*
X907765Y-151356D01*
Y-137648D01*
G01Y-139981D02*
X906892Y-138814D01*
X905581Y-137939D01*
X904053Y-137648D01*
X902307Y-138231D01*
X901215Y-139397D01*
X900341Y-141439D01*
X899905Y-143481D01*
X900123Y-145231D01*
X900997Y-147273D01*
X902307Y-148731D01*
X904053Y-149314D01*
X905363Y-149022D01*
X906892Y-147856D01*
X907765Y-146690D01*
G01X917623Y-149314D02*
Y-137648D01*
G01Y-140564D02*
X918497Y-139106D01*
X919807Y-137939D01*
X921553Y-137648D01*
X923081Y-137939D01*
X924392Y-139106D01*
X925047Y-141147D01*
Y-149314D01*
G01X935560Y-141439D02*
X942547D01*
X941892Y-139397D01*
X940800Y-138231D01*
X939272Y-137648D01*
X937743Y-137939D01*
X936433Y-138814D01*
X935560Y-140856D01*
X935123Y-142606D01*
Y-144356D01*
X935560Y-146106D01*
X936652Y-147856D01*
X937962Y-149022D01*
X939490Y-149314D01*
X941018Y-148731D01*
X942547Y-146981D01*
G01X953278Y-149314D02*
Y-137648D01*
G01Y-139981D02*
X954370Y-138814D01*
X955462Y-137939D01*
X956990Y-137648D01*
X958081Y-137939D01*
X959392Y-138814D01*
G01X1000035Y-176814D02*
X998288Y-177397D01*
X996978Y-178856D01*
X996105Y-180605D01*
X995450Y-182939D01*
X995232Y-185564D01*
X995450Y-188189D01*
X996105Y-190523D01*
X996978Y-192273D01*
X998288Y-193731D01*
X1000035Y-194314D01*
X1001781Y-193731D01*
X1003092Y-192273D01*
X1003965Y-190523D01*
X1004620Y-188189D01*
X1004838Y-185564D01*
X1004620Y-182939D01*
X1003965Y-180605D01*
X1003092Y-178856D01*
X1001781Y-177397D01*
X1000035Y-176814D01*
G01X1012732Y-190814D02*
X1014041Y-192856D01*
X1015788Y-194022D01*
X1017753Y-194314D01*
X1019500Y-194022D01*
X1021247Y-192564D01*
X1022338Y-190814D01*
X1022557Y-189064D01*
X1022120Y-187023D01*
X1020592Y-185564D01*
X1019063Y-184981D01*
X1017098D01*
G01X1019063D02*
X1020373Y-184106D01*
X1021465Y-182648D01*
X1021902Y-180898D01*
X1021465Y-179147D01*
X1020373Y-177689D01*
X1018408Y-176814D01*
X1016443Y-177106D01*
X1014478Y-178273D01*
G01X1031105Y-194897D02*
X1038965Y-176814D01*
G01X1052535Y-194314D02*
Y-176814D01*
X1049915Y-180314D01*
G01Y-194314D02*
X1055155D01*
G01X1065232Y-190814D02*
X1066541Y-192856D01*
X1068288Y-194022D01*
X1070253Y-194314D01*
X1072000Y-194022D01*
X1073747Y-192564D01*
X1074838Y-190814D01*
X1075057Y-189064D01*
X1074620Y-187023D01*
X1073092Y-185564D01*
X1071563Y-184981D01*
X1069598D01*
G01X1071563D02*
X1072873Y-184106D01*
X1073965Y-182648D01*
X1074402Y-180898D01*
X1073965Y-179147D01*
X1072873Y-177689D01*
X1070908Y-176814D01*
X1068943Y-177106D01*
X1066978Y-178273D01*
G01X1083605Y-194897D02*
X1091465Y-176814D01*
G01X1100887Y-179731D02*
X1102197Y-177981D01*
X1103725Y-177106D01*
X1105472Y-176814D01*
X1107655Y-177397D01*
X1109183Y-178856D01*
X1109620Y-180605D01*
X1109402Y-182356D01*
X1108528Y-183814D01*
X1104162Y-186731D01*
X1102197Y-188772D01*
X1100887Y-191690D01*
X1100450Y-194314D01*
X1109620D01*
G01X1122535Y-176814D02*
X1120788Y-177397D01*
X1119478Y-178856D01*
X1118605Y-180605D01*
X1117950Y-182939D01*
X1117732Y-185564D01*
X1117950Y-188189D01*
X1118605Y-190523D01*
X1119478Y-192273D01*
X1120788Y-193731D01*
X1122535Y-194314D01*
X1124281Y-193731D01*
X1125592Y-192273D01*
X1126465Y-190523D01*
X1127120Y-188189D01*
X1127338Y-185564D01*
X1127120Y-182939D01*
X1126465Y-180605D01*
X1125592Y-178856D01*
X1124281Y-177397D01*
X1122535Y-176814D01*
G01X1140035Y-194314D02*
Y-176814D01*
X1137415Y-180314D01*
G01Y-194314D02*
X1142655D01*
G01X1157098D02*
X1157535Y-190523D01*
X1158190Y-187314D01*
X1159063Y-184397D01*
X1160155Y-181189D01*
X1161902Y-176814D01*
X1153168D01*
G01X1047732Y-149314D02*
Y-131814D01*
X1052098D01*
X1053845Y-132689D01*
X1055155Y-133856D01*
X1056247Y-135605D01*
X1057120Y-137648D01*
X1057338Y-140564D01*
X1057120Y-143481D01*
X1056247Y-145523D01*
X1055155Y-147273D01*
X1053845Y-148439D01*
X1052098Y-149314D01*
X1047732D01*
G01X1073965D02*
Y-137648D01*
G01Y-139689D02*
X1073092Y-138523D01*
X1071781Y-137939D01*
X1070253Y-137648D01*
X1068725Y-138231D01*
X1067415Y-139397D01*
X1066541Y-141147D01*
X1066105Y-143481D01*
X1066541Y-145814D01*
X1067415Y-147564D01*
X1068725Y-148731D01*
X1070253Y-149314D01*
X1071781Y-149022D01*
X1073092Y-148148D01*
X1073965Y-146981D01*
G01X1087535Y-131814D02*
Y-149314D01*
G01X1084478Y-137648D02*
X1090592D01*
G01X1101760Y-141439D02*
X1108747D01*
X1108092Y-139397D01*
X1107000Y-138231D01*
X1105472Y-137648D01*
X1103943Y-137939D01*
X1102633Y-138814D01*
X1101760Y-140856D01*
X1101323Y-142606D01*
Y-144356D01*
X1101760Y-146106D01*
X1102852Y-147856D01*
X1104162Y-149022D01*
X1105690Y-149314D01*
X1107218Y-148731D01*
X1108747Y-146981D01*
M02*
